# TIMECARD (Time Appliance Project (Time Card)) — schematic netlist excerpt (pin names and nets, part order shuffled) for the footprints in the layout excerpt that follows; sources: Cadence DE-HDL packaged netlist, KiCad conversion of R4006-B0001-02_R01.brd

C93  CAPACITOR  4.7UF 6.3V 20%  pkg SMC_0402R_H026  page 14 : \1\ = XP2R5V_FPGA ; \2\ = SG
R49  RESISTOR  10KOHM 1%  pkg SMC_0402R_H016  page 32 : \1\ = VIN_XP5R0V ; \2\ = R_XP5R0V_EN

(kicad_pcb
	(version 20260206)
	(generator "pcbnew")
	(generator_version "10.0")
	(general
		(thickness 1.6)
		(legacy_teardrops no)
	)
	(paper "A4")
	(title_block
		(title "timecard-production-celestica-r4006 — R4006-B0001-02_R01.brd")
		(comment 1 "Time Appliance Project (Time Card) / footprints 730-731 of 1113")
	)
	(layers
		(0 "F.Cu" signal "TOP")
		(4 "In1.Cu" signal "L02_GND1")
		(6 "In2.Cu" signal "L03_SIG1")
		(8 "In3.Cu" signal "L04_GND2")
		(10 "In4.Cu" signal "L05_VCC1")
		(12 "In5.Cu" signal "L06_VCC2")
		(14 "In6.Cu" signal "L07_GND3")
		(16 "In7.Cu" signal "L08_SIG2")
		(18 "In8.Cu" signal "L09_GND4")
		(2 "B.Cu" signal "BOTTOM")
		(9 "F.Adhes" user "F.Adhesive")
		(11 "B.Adhes" user "B.Adhesive")
		(13 "F.Paste" user "Package Geometry/Pastemask Top")
		(15 "B.Paste" user "Package Geometry/Pastemask Bottom")
		(5 "F.SilkS" user "Ref Des/Silkscreen Top")
		(7 "B.SilkS" user "Ref Des/Silkscreen Bottom")
		(1 "F.Mask" user "Board Geometry/Soldermask Top")
		(3 "B.Mask" user "Board Geometry/Soldermask Bottom")
		(17 "Dwgs.User" user "User.Drawings")
		(19 "Cmts.User" user "User.Comments")
		(21 "Eco1.User" user "User.Eco1")
		(23 "Eco2.User" user "User.Eco2")
		(25 "Edge.Cuts" user "Board Geometry/Outline")
		(27 "Margin" user)
		(31 "F.CrtYd" user "Package Geometry/Place Bound Top")
		(29 "B.CrtYd" user "Package Geometry/Place Bound Bottom")
		(35 "F.Fab" user "Ref Des/Assembly Top")
		(33 "B.Fab" user "Ref Des/Assembly Bottom")
	)
	(footprint ""
		(layer "B.Cu")
		(at 39.6494 -95.9104)
		(property "Reference" "R49"
			(at 0.4826 1.20777 0)
			(unlocked yes)
			(layer "B.SilkS")
			(effects
				(font
					(size 0.7874 0.5842)
					(thickness 0.1524)
				)
				(justify mirror)
			)
		)
		(property "Value" "VAL*"
			(at -0.02032 2.13233 0)
			(unlocked yes)
			(layer "B.Fab")
			(hide yes)
			(effects
				(font
					(size 0.7874 0.5842)
					(thickness 0.1524)
				)
				(justify mirror)
			)
		)
		(property "Tolerance" "TOL*"
			(at -0.044704 3.05435 0)
			(unlocked yes)
			(layer "Cmts.User")
			(hide yes)
			(effects
				(font
					(size 0.7874 0.5842)
					(thickness 0.1524)
				)
				(justify mirror)
			)
		)
		(property "User Part Number" "PARTNUM*"
			(at -0.02032 4.024884 0)
			(unlocked yes)
			(layer "Cmts.User")
			(hide yes)
			(effects
				(font
					(size 0.7874 0.5842)
					(thickness 0.1524)
				)
				(justify mirror)
			)
		)
		(property "Device Type" "RESISTOR-G155-11002-01,10KOHM,A"
			(at -0.008382 1.210564 0)
			(unlocked yes)
			(layer "B.Fab")
			(hide yes)
			(effects
				(font
					(size 0.7874 0.5842)
					(thickness 0.1524)
				)
				(justify mirror)
			)
		)
		(duplicate_pad_numbers_are_jumpers no)
		(fp_line
			(start -1.143 -0.5588)
			(end 1.143 -0.5588)
			(stroke
				(width 0.1)
				(type default)
			)
			(layer "B.SilkS")
		)
		(fp_line
			(start -1.143 0.5588)
			(end -1.143 -0.5588)
			(stroke
				(width 0.1)
				(type default)
			)
			(layer "B.SilkS")
		)
		(fp_line
			(start 1.143 -0.5588)
			(end 1.143 0.5588)
			(stroke
				(width 0.1)
				(type default)
			)
			(layer "B.SilkS")
		)
		(fp_line
			(start 1.143 0.5588)
			(end -1.143 0.5588)
			(stroke
				(width 0.1)
				(type default)
			)
			(layer "B.SilkS")
		)
		(fp_poly
			(pts
				(xy 1.143 0.5588) (xy -1.143 0.5588) (xy -1.143 -0.5588) (xy 1.143 -0.5588)
			)
			(stroke
				(width 0)
				(type default)
			)
			(fill no)
			(layer "B.CrtYd")
		)
		(fp_line
			(start -0.508 -0.3048)
			(end 0.508 -0.3048)
			(stroke
				(width 0.1)
				(type default)
			)
			(layer "B.Fab")
		)
		(fp_line
			(start -0.508 0.3048)
			(end -0.508 -0.3048)
			(stroke
				(width 0.1)
				(type default)
			)
			(layer "B.Fab")
		)
		(fp_line
			(start 0.508 -0.3048)
			(end 0.508 0.3048)
			(stroke
				(width 0.1)
				(type default)
			)
			(layer "B.Fab")
		)
		(fp_line
			(start 0.508 0.3048)
			(end -0.508 0.3048)
			(stroke
				(width 0.1)
				(type default)
			)
			(layer "B.Fab")
		)
		(pad "1" smd rect
			(at 0.5334 0 180)
			(size 0.7112 0.6096)
			(layers "B.Cu" "B.Mask" "B.Paste")
			(net "VIN_XP5R0V")
		)
		(pad "2" smd rect
			(at -0.5334 0 180)
			(size 0.7112 0.6096)
			(layers "B.Cu" "B.Mask" "B.Paste")
			(net "R_XP5R0V_EN")
		)
		(zone
			(layer "B.Cu")
			(hatch none 0.5)
			(connect_pads
				(clearance 0)
			)
			(min_thickness 0.25)
			(keepout
				(tracks not_allowed)
				(vias allowed)
				(pads allowed)
				(copperpour not_allowed)
				(footprints allowed)
			)
			(placement
				(enabled no)
				(sheetname "")
			)
			(fill
				(thermal_gap 0.5)
				(thermal_bridge_width 0.5)
				(island_removal_mode 0)
			)
			(polygon
				(pts
					(xy 39.7256 -95.6056) (xy 39.7256 -96.2152) (xy 39.5732 -96.2152) (xy 39.5732 -95.6056)
				)
			)
		)
		(zone
			(layer "B.Cu")
			(hatch none 0.5)
			(connect_pads
				(clearance 0)
			)
			(min_thickness 0.25)
			(keepout
				(tracks allowed)
				(vias not_allowed)
				(pads allowed)
				(copperpour not_allowed)
				(footprints allowed)
			)
			(placement
				(enabled no)
				(sheetname "")
			)
			(fill
				(thermal_gap 0.5)
				(thermal_bridge_width 0.5)
				(island_removal_mode 0)
			)
			(polygon
				(pts
					(xy 39.7256 -95.6056) (xy 39.7256 -96.2152) (xy 39.5732 -96.2152) (xy 39.5732 -95.6056)
				)
			)
		)
	)
	(footprint ""
		(layer "B.Cu")
		(at 116.847112 -39.323264 -90)
		(property "Reference" "C93"
			(at -0.173736 0.927862 270)
			(unlocked yes)
			(layer "B.SilkS")
			(effects
				(font
					(size 0.635 0.4064)
					(thickness 0.1524)
				)
				(justify mirror)
			)
		)
		(property "Value" "VAL*"
			(at 0 3.718306 270)
			(unlocked yes)
			(layer "B.Fab")
			(hide yes)
			(effects
				(font
					(size 0.7874 0.5842)
					(thickness 0.127)
				)
				(justify mirror)
			)
		)
		(property "Tolerance" "TOL*"
			(at 0 4.861306 270)
			(unlocked yes)
			(layer "Cmts.User")
			(hide yes)
			(effects
				(font
					(size 0.7874 0.5842)
					(thickness 0.127)
				)
				(justify mirror)
			)
		)
		(property "User Part Number" "PARTNUM*"
			(at 0 2.575306 270)
			(unlocked yes)
			(layer "Cmts.User")
			(hide yes)
			(effects
				(font
					(size 0.7874 0.5842)
					(thickness 0.127)
				)
				(justify mirror)
			)
		)
		(property "Device Type" "CAPACITOR-G105-0F475-BM,4.7UF,A"
			(at 0 1.432306 270)
			(unlocked yes)
			(layer "B.Fab")
			(hide yes)
			(effects
				(font
					(size 0.7874 0.5842)
					(thickness 0.127)
				)
				(justify mirror)
			)
		)
		(duplicate_pad_numbers_are_jumpers no)
		(fp_line
			(start -0.970026 0.4699)
			(end 0.970026 0.4699)
			(stroke
				(width 0.1)
				(type default)
			)
			(layer "B.SilkS")
		)
		(fp_line
			(start 0.970026 0.4699)
			(end 0.970026 -0.4699)
			(stroke
				(width 0.1)
				(type default)
			)
			(layer "B.SilkS")
		)
		(fp_line
			(start -0.970026 -0.4699)
			(end -0.970026 0.4699)
			(stroke
				(width 0.1)
				(type default)
			)
			(layer "B.SilkS")
		)
		(fp_line
			(start 0.970026 -0.4699)
			(end -0.970026 -0.4699)
			(stroke
				(width 0.1)
				(type default)
			)
			(layer "B.SilkS")
		)
		(fp_poly
			(pts
				(xy 0.970026 0.4699) (xy -0.970026 0.4699) (xy -0.970026 -0.4699) (xy 0.970026 -0.4699)
			)
			(stroke
				(width 0)
				(type default)
			)
			(fill no)
			(layer "B.CrtYd")
		)
		(fp_line
			(start -0.508 0.3048)
			(end 0.508 0.3048)
			(stroke
				(width 0.1)
				(type default)
			)
			(layer "B.Fab")
		)
		(fp_line
			(start 0.508 0.3048)
			(end 0.508 -0.3048)
			(stroke
				(width 0.1)
				(type default)
			)
			(layer "B.Fab")
		)
		(fp_line
			(start -0.508 -0.3048)
			(end -0.508 0.3048)
			(stroke
				(width 0.1)
				(type default)
			)
			(layer "B.Fab")
		)
		(fp_line
			(start 0.508 -0.3048)
			(end -0.508 -0.3048)
			(stroke
				(width 0.1)
				(type default)
			)
			(layer "B.Fab")
		)
		(pad "1" smd circle
			(at 0.500126 0 90)
			(size 0.635 0.635)
			(layers "B.Cu" "B.Mask" "B.Paste")
			(net "XP2R5V_FPGA")
		)
		(pad "2" smd circle
			(at -0.500126 0 90)
			(size 0.635 0.635)
			(layers "B.Cu" "B.Mask" "B.Paste")
			(net "SG")
		)
	)
)
